(kicad_pcb
	(version 20241229)
	(generator "pcbnew")
	(generator_version "9.0")
	(general
		(thickness 1.711)
		(legacy_teardrops no)
	)
	(paper "A4")
	(title_block
		(title "Antmicro Baseboard for Jetson AGX Thor")
		(date "2026-02-18")
		(rev "1.1.0")
		(company "Antmicro Ltd")
		(comment 1 "www.antmicro.com")
		(comment 9 "footprints 251-255 of 1170")
	)
	(layers
		(0 "F.Cu" signal)
		(4 "In1.Cu" signal)
		(6 "In2.Cu" signal)
		(8 "In3.Cu" signal)
		(10 "In4.Cu" jumper)
		(12 "In5.Cu" signal)
		(14 "In6.Cu" signal)
		(16 "In7.Cu" signal)
		(18 "In8.Cu" signal)
		(2 "B.Cu" signal)
		(9 "F.Adhes" user "F.Adhesive")
		(11 "B.Adhes" user "B.Adhesive")
		(13 "F.Paste" user)
		(15 "B.Paste" user)
		(5 "F.SilkS" user "F.Silkscreen")
		(7 "B.SilkS" user "B.Silkscreen")
		(1 "F.Mask" user)
		(3 "B.Mask" user)
		(17 "Dwgs.User" user "User.Drawings")
		(19 "Cmts.User" user "User.Comments")
		(21 "Eco1.User" user "User.Eco1")
		(23 "Eco2.User" user "User.Eco2")
		(25 "Edge.Cuts" user)
		(27 "Margin" user)
		(31 "F.CrtYd" user "F.Courtyard")
		(29 "B.CrtYd" user "B.Courtyard")
		(35 "F.Fab" user)
		(33 "B.Fab" user)
	)
	(footprint "antmicro-footprints:R_0402_1005Metric"
		(layer "F.Cu")
		(at 216.2 78)
		(descr "Resistor SMD 0402")
		(tags "resistor SMD 0402")
		(property "Reference" "R124"
			(at 1.3 0.6 180)
			(layer "F.SilkS")
			(effects
				(font
					(size 0.7 0.7)
					(thickness 0.15)
				)
				(justify right top)
			)
		)
		(property "Value" "R_0R_0402"
			(at -1.011843 1.772047 180)
			(layer "F.Fab")
			(effects
				(font
					(size 0.7 0.7)
					(thickness 0.15)
				)
				(justify right top)
			)
		)
		(property "Datasheet" "https://industrial.panasonic.com/cdbs/www-data/pdf/RDA0000/AOA0000C301.pdf"
			(at 0 0 180)
			(layer "F.Fab")
			(hide yes)
			(effects
				(font
					(size 1.27 1.27)
					(thickness 0.15)
				)
			)
		)
		(property "Description" "SMD Chip Resistor, Jumper, 0 ohm, 100 mW, 0402 [1005 Metric], Thick Film, General Purpose"
			(at 0 0 180)
			(layer "F.Fab")
			(hide yes)
			(effects
				(font
					(size 1.27 1.27)
					(thickness 0.15)
				)
			)
		)
		(property "Manufacturer" "Panasonic"
			(at 0 0 0)
			(unlocked yes)
			(layer "F.Fab")
			(hide yes)
			(effects
				(font
					(size 1 1)
					(thickness 0.15)
				)
			)
		)
		(property "MPN" "ERJ2GE0R00X"
			(at 0 0 0)
			(unlocked yes)
			(layer "F.Fab")
			(hide yes)
			(effects
				(font
					(size 1 1)
					(thickness 0.15)
				)
			)
		)
		(property "Val" "0R"
			(at 0 0 0)
			(unlocked yes)
			(layer "F.Fab")
			(hide yes)
			(effects
				(font
					(size 1 1)
					(thickness 0.15)
				)
			)
		)
		(property "License" "Apache-2.0"
			(at 0 0 0)
			(unlocked yes)
			(layer "F.Fab")
			(hide yes)
			(effects
				(font
					(size 1 1)
					(thickness 0.15)
				)
			)
		)
		(property "Author" "Antmicro"
			(at 0 0 0)
			(unlocked yes)
			(layer "F.Fab")
			(hide yes)
			(effects
				(font
					(size 1 1)
					(thickness 0.15)
				)
			)
		)
		(property "Tolerance" "~"
			(at 0 0 0)
			(unlocked yes)
			(layer "F.Fab")
			(hide yes)
			(effects
				(font
					(size 1 1)
					(thickness 0.15)
				)
			)
		)
		(property "Current" "1A"
			(at 0 0 0)
			(unlocked yes)
			(layer "F.Fab")
			(hide yes)
			(effects
				(font
					(size 1 1)
					(thickness 0.15)
				)
			)
		)
		(sheetname "/USB Debug, PD/")
		(sheetfile "usb_debug_pd.kicad_sch")
		(attr smd)
		(fp_rect
			(start -0.925 -0.47)
			(end 0.925 0.47)
			(stroke
				(width 0.05)
				(type default)
			)
			(fill no)
			(layer "F.CrtYd")
		)
		(fp_rect
			(start -0.5 -0.25)
			(end 0.5 0.25)
			(stroke
				(width 0.15)
				(type solid)
			)
			(fill no)
			(layer "F.Fab")
		)
		(fp_text user "${REFERENCE}"
			(at -0.95 3.168 180)
			(layer "F.Fab")
			(effects
				(font
					(size 0.7 0.7)
					(thickness 0.15)
				)
				(justify right top)
			)
		)
		(fp_text user "Author: Antmicro"
			(at -0.95 4.169 180)
			(layer "F.Fab")
			(effects
				(font
					(size 0.7 0.7)
					(thickness 0.15)
				)
				(justify right top)
			)
		)
		(fp_text user "License: Apache-2.0"
			(at -0.95 5.169 180)
			(layer "F.Fab")
			(effects
				(font
					(size 0.7 0.7)
					(thickness 0.15)
				)
				(justify right top)
			)
		)
		(pad "1" smd roundrect
			(at -0.48 0)
			(size 0.59 0.64)
			(layers "F.Cu" "F.Mask" "F.Paste")
			(roundrect_rratio 0.25)
			(net 960 "/SoM_IO/UART3_DEBUG.RX")
			(pintype "passive")
		)
		(pad "2" smd roundrect
			(at 0.48 0)
			(size 0.59 0.64)
			(layers "F.Cu" "F.Mask" "F.Paste")
			(roundrect_rratio 0.25)
			(net 958 "Net-(U34-TXD)")
			(pintype "passive")
		)
	)
	(footprint "antmicro-footprints:R_0402_1005Metric"
		(layer "F.Cu")
		(at 139.7 111.72 -90)
		(descr "Resistor SMD 0402")
		(tags "resistor SMD 0402")
		(property "Reference" "R404"
			(at 0.78 0.4 90)
			(layer "F.SilkS")
			(effects
				(font
					(size 0.7 0.7)
					(thickness 0.15)
				)
				(justify right top)
			)
		)
		(property "Value" "R_0R_0402"
			(at -1.011843 1.772047 90)
			(layer "F.Fab")
			(effects
				(font
					(size 0.7 0.7)
					(thickness 0.15)
				)
				(justify right top)
			)
		)
		(property "Datasheet" "https://industrial.panasonic.com/cdbs/www-data/pdf/RDA0000/AOA0000C301.pdf"
			(at 0 0 90)
			(layer "F.Fab")
			(hide yes)
			(effects
				(font
					(size 1.27 1.27)
					(thickness 0.15)
				)
			)
		)
		(property "Description" "SMD Chip Resistor, Jumper, 0 ohm, 100 mW, 0402 [1005 Metric], Thick Film, General Purpose"
			(at 0 0 90)
			(layer "F.Fab")
			(hide yes)
			(effects
				(font
					(size 1.27 1.27)
					(thickness 0.15)
				)
			)
		)
		(property "MPN" "ERJ2GE0R00X"
			(at 0 0 270)
			(unlocked yes)
			(layer "F.Fab")
			(hide yes)
			(effects
				(font
					(size 1 1)
					(thickness 0.15)
				)
			)
		)
		(property "Manufacturer" "Panasonic"
			(at 0 0 270)
			(unlocked yes)
			(layer "F.Fab")
			(hide yes)
			(effects
				(font
					(size 1 1)
					(thickness 0.15)
				)
			)
		)
		(property "License" "Apache-2.0"
			(at 0 0 270)
			(unlocked yes)
			(layer "F.Fab")
			(hide yes)
			(effects
				(font
					(size 1 1)
					(thickness 0.15)
				)
			)
		)
		(property "Author" "Antmicro"
			(at 0 0 270)
			(unlocked yes)
			(layer "F.Fab")
			(hide yes)
			(effects
				(font
					(size 1 1)
					(thickness 0.15)
				)
			)
		)
		(property "Val" "0R"
			(at 0 0 270)
			(unlocked yes)
			(layer "F.Fab")
			(hide yes)
			(effects
				(font
					(size 1 1)
					(thickness 0.15)
				)
			)
		)
		(property "Tolerance" "~"
			(at 0 0 270)
			(unlocked yes)
			(layer "F.Fab")
			(hide yes)
			(effects
				(font
					(size 1 1)
					(thickness 0.15)
				)
			)
		)
		(property "Current" "1A"
			(at 0 0 270)
			(unlocked yes)
			(layer "F.Fab")
			(hide yes)
			(effects
				(font
					(size 1 1)
					(thickness 0.15)
				)
			)
		)
		(sheetname "/Peripherals/")
		(sheetfile "peripherals.kicad_sch")
		(attr smd)
		(fp_rect
			(start -0.925 -0.47)
			(end 0.925 0.47)
			(stroke
				(width 0.05)
				(type default)
			)
			(fill no)
			(layer "F.CrtYd")
		)
		(fp_rect
			(start -0.5 -0.25)
			(end 0.5 0.25)
			(stroke
				(width 0.15)
				(type solid)
			)
			(fill no)
			(layer "F.Fab")
		)
		(fp_text user "Author: Antmicro"
			(at -0.95 4.169 90)
			(layer "F.Fab")
			(effects
				(font
					(size 0.7 0.7)
					(thickness 0.15)
				)
				(justify right top)
			)
		)
		(fp_text user "${REFERENCE}"
			(at -0.95 3.168 90)
			(layer "F.Fab")
			(effects
				(font
					(size 0.7 0.7)
					(thickness 0.15)
				)
				(justify right top)
			)
		)
		(fp_text user "License: Apache-2.0"
			(at -0.95 5.169 90)
			(layer "F.Fab")
			(effects
				(font
					(size 0.7 0.7)
					(thickness 0.15)
				)
				(justify right top)
			)
		)
		(pad "1" smd roundrect
			(at -0.48 0 270)
			(size 0.59 0.64)
			(layers "F.Cu" "F.Mask" "F.Paste")
			(roundrect_rratio 0.25)
			(net 1317 "/Peripherals/GPIOEX_P0_5")
			(pintype "passive")
		)
		(pad "2" smd roundrect
			(at 0.48 0 270)
			(size 0.59 0.64)
			(layers "F.Cu" "F.Mask" "F.Paste")
			(roundrect_rratio 0.25)
			(net 149 "/Peripherals/TPM_IRQ")
			(pintype "passive")
		)
	)
	(footprint "antmicro-footprints:C_0402_1005Metric"
		(layer "F.Cu")
		(at 193.126 142.275 180)
		(descr "Capacitor SMD 0402")
		(tags "capacitor SMD 0402")
		(property "Reference" "C65"
			(at 3.226 -0.325 180)
			(layer "F.SilkS")
			(effects
				(font
					(size 0.7 0.7)
					(thickness 0.15)
				)
				(justify left bottom)
			)
		)
		(property "Value" "C_100n_0402"
			(at -1.022927 2.155213 180)
			(layer "F.Fab")
			(effects
				(font
					(size 0.7 0.7)
					(thickness 0.15)
				)
				(justify left bottom)
			)
		)
		(property "Datasheet" "https://www.murata.com/products/productdetail?partno=GRM155R61H104KE14%23"
			(at 0 0 180)
			(layer "F.Fab")
			(hide yes)
			(effects
				(font
					(size 1.27 1.27)
					(thickness 0.15)
				)
			)
		)
		(property "Description" "SMD Multilayer Ceramic Capacitor, 0.1 µF, 50 V, 0402 [1005 Metric], ± 10%, X5R, GRM Series"
			(at 0 0 180)
			(layer "F.Fab")
			(hide yes)
			(effects
				(font
					(size 1.27 1.27)
					(thickness 0.15)
				)
			)
		)
		(property "Manufacturer" "Murata"
			(at 0 0 180)
			(unlocked yes)
			(layer "F.Fab")
			(hide yes)
			(effects
				(font
					(size 1 1)
					(thickness 0.15)
				)
			)
		)
		(property "MPN" "GRM155R61H104KE14D"
			(at 0 0 180)
			(unlocked yes)
			(layer "F.Fab")
			(hide yes)
			(effects
				(font
					(size 1 1)
					(thickness 0.15)
				)
			)
		)
		(property "Val" "100n"
			(at 0 0 180)
			(unlocked yes)
			(layer "F.Fab")
			(hide yes)
			(effects
				(font
					(size 1 1)
					(thickness 0.15)
				)
			)
		)
		(property "License" "Apache-2.0"
			(at 0 0 180)
			(unlocked yes)
			(layer "F.Fab")
			(hide yes)
			(effects
				(font
					(size 1 1)
					(thickness 0.15)
				)
			)
		)
		(property "Author" "Antmicro"
			(at 0 0 180)
			(unlocked yes)
			(layer "F.Fab")
			(hide yes)
			(effects
				(font
					(size 1 1)
					(thickness 0.15)
				)
			)
		)
		(property "Voltage" "50V"
			(at 0 0 180)
			(unlocked yes)
			(layer "F.Fab")
			(hide yes)
			(effects
				(font
					(size 1 1)
					(thickness 0.15)
				)
			)
		)
		(property "Dielectric" "X5R"
			(at 0 0 180)
			(unlocked yes)
			(layer "F.Fab")
			(hide yes)
			(effects
				(font
					(size 1 1)
					(thickness 0.15)
				)
			)
		)
		(property "Public" "False"
			(at 0 0 180)
			(unlocked yes)
			(layer "F.Fab")
			(hide yes)
			(effects
				(font
					(size 1 1)
					(thickness 0.15)
				)
			)
		)
		(sheetname "/SFP/")
		(sheetfile "sfp.kicad_sch")
		(attr smd)
		(fp_rect
			(start -0.925 -0.47)
			(end 0.925 0.47)
			(stroke
				(width 0.05)
				(type default)
			)
			(fill no)
			(layer "F.CrtYd")
		)
		(fp_line
			(start 0.504 0.248)
			(end -0.494 0.248)
			(stroke
				(width 0.15)
				(type solid)
			)
			(layer "F.Fab")
		)
		(fp_line
			(start 0.504 -0.25)
			(end 0.504 0.248)
			(stroke
				(width 0.15)
				(type solid)
			)
			(layer "F.Fab")
		)
		(fp_line
			(start -0.494 0.248)
			(end -0.494 -0.25)
			(stroke
				(width 0.15)
				(type solid)
			)
			(layer "F.Fab")
		)
		(fp_line
			(start -0.494 -0.25)
			(end 0.504 -0.25)
			(stroke
				(width 0.15)
				(type solid)
			)
			(layer "F.Fab")
		)
		(fp_text user "License: Apache-2.0"
			(at -0.939 5.799 180)
			(layer "F.Fab")
			(effects
				(font
					(size 0.7 0.7)
					(thickness 0.15)
				)
				(justify left bottom)
			)
		)
		(fp_text user "${REFERENCE}"
			(at -0.939 4.599 180)
			(layer "F.Fab")
			(effects
				(font
					(size 0.7 0.7)
					(thickness 0.15)
				)
				(justify left bottom)
			)
		)
		(fp_text user "Author: Antmicro"
			(at -0.939 3.399 180)
			(layer "F.Fab")
			(effects
				(font
					(size 0.7 0.7)
					(thickness 0.15)
				)
				(justify left bottom)
			)
		)
		(pad "1" smd roundrect
			(at -0.48 0 180)
			(size 0.59 0.64)
			(layers "F.Cu" "F.Mask" "F.Paste")
			(roundrect_rratio 0.25)
			(net 30 "/SFP/SFI_CONN_RX_N")
			(pintype "passive")
		)
		(pad "2" smd roundrect
			(at 0.48 0 180)
			(size 0.59 0.64)
			(layers "F.Cu" "F.Mask" "F.Paste")
			(roundrect_rratio 0.25)
			(net 147 "/SFP/SFI.RX-")
			(pintype "passive")
		)
	)
	(footprint "antmicro-footprints:C_0402_1005Metric"
		(layer "F.Cu")
		(at 218.8 111.7 180)
		(descr "Capacitor SMD 0402")
		(tags "capacitor SMD 0402")
		(property "Reference" "C113"
			(at 0.9 0.4 0)
			(layer "F.SilkS")
			(effects
				(font
					(size 0.7 0.7)
					(thickness 0.15)
				)
				(justify right top)
			)
		)
		(property "Value" "C_100n_0402"
			(at -1.022927 2.155213 0)
			(layer "F.Fab")
			(effects
				(font
					(size 0.7 0.7)
					(thickness 0.15)
				)
				(justify right top)
			)
		)
		(property "Datasheet" "https://www.murata.com/products/productdetail?partno=GRM155R61H104KE14%23"
			(at 0 0 0)
			(layer "F.Fab")
			(hide yes)
			(effects
				(font
					(size 1.27 1.27)
					(thickness 0.15)
				)
			)
		)
		(property "Description" "SMD Multilayer Ceramic Capacitor, 0.1 µF, 50 V, 0402 [1005 Metric], ± 10%, X5R, GRM Series"
			(at 0 0 0)
			(layer "F.Fab")
			(hide yes)
			(effects
				(font
					(size 1.27 1.27)
					(thickness 0.15)
				)
			)
		)
		(property "Manufacturer" "Murata"
			(at 0 0 180)
			(unlocked yes)
			(layer "F.Fab")
			(hide yes)
			(effects
				(font
					(size 1 1)
					(thickness 0.15)
				)
			)
		)
		(property "MPN" "GRM155R61H104KE14D"
			(at 0 0 180)
			(unlocked yes)
			(layer "F.Fab")
			(hide yes)
			(effects
				(font
					(size 1 1)
					(thickness 0.15)
				)
			)
		)
		(property "Val" "100n"
			(at 0 0 180)
			(unlocked yes)
			(layer "F.Fab")
			(hide yes)
			(effects
				(font
					(size 1 1)
					(thickness 0.15)
				)
			)
		)
		(property "License" "Apache-2.0"
			(at 0 0 180)
			(unlocked yes)
			(layer "F.Fab")
			(hide yes)
			(effects
				(font
					(size 1 1)
					(thickness 0.15)
				)
			)
		)
		(property "Author" "Antmicro"
			(at 0 0 180)
			(unlocked yes)
			(layer "F.Fab")
			(hide yes)
			(effects
				(font
					(size 1 1)
					(thickness 0.15)
				)
			)
		)
		(property "Voltage" "50V"
			(at 0 0 180)
			(unlocked yes)
			(layer "F.Fab")
			(hide yes)
			(effects
				(font
					(size 1 1)
					(thickness 0.15)
				)
			)
		)
		(property "Dielectric" "X5R"
			(at 0 0 180)
			(unlocked yes)
			(layer "F.Fab")
			(hide yes)
			(effects
				(font
					(size 1 1)
					(thickness 0.15)
				)
			)
		)
		(sheetname "/USB Hub/")
		(sheetfile "usb_hub.kicad_sch")
		(attr smd)
		(fp_rect
			(start -0.925 -0.47)
			(end 0.925 0.47)
			(stroke
				(width 0.05)
				(type default)
			)
			(fill no)
			(layer "F.CrtYd")
		)
		(fp_line
			(start 0.504 0.248)
			(end -0.494 0.248)
			(stroke
				(width 0.15)
				(type solid)
			)
			(layer "F.Fab")
		)
		(fp_line
			(start 0.504 -0.25)
			(end 0.504 0.248)
			(stroke
				(width 0.15)
				(type solid)
			)
			(layer "F.Fab")
		)
		(fp_line
			(start -0.494 0.248)
			(end -0.494 -0.25)
			(stroke
				(width 0.15)
				(type solid)
			)
			(layer "F.Fab")
		)
		(fp_line
			(start -0.494 -0.25)
			(end 0.504 -0.25)
			(stroke
				(width 0.15)
				(type solid)
			)
			(layer "F.Fab")
		)
		(fp_text user "License: Apache-2.0"
			(at -0.939 5.799 0)
			(layer "F.Fab")
			(effects
				(font
					(size 0.7 0.7)
					(thickness 0.15)
				)
				(justify right top)
			)
		)
		(fp_text user "Author: Antmicro"
			(at -0.939 3.399 0)
			(layer "F.Fab")
			(effects
				(font
					(size 0.7 0.7)
					(thickness 0.15)
				)
				(justify right top)
			)
		)
		(fp_text user "${REFERENCE}"
			(at -0.939 4.599 0)
			(layer "F.Fab")
			(effects
				(font
					(size 0.7 0.7)
					(thickness 0.15)
				)
				(justify right top)
			)
		)
		(pad "1" smd roundrect
			(at -0.48 0 180)
			(size 0.59 0.64)
			(layers "F.Cu" "F.Mask" "F.Paste")
			(roundrect_rratio 0.25)
			(net 174 "/USB Hub/USBC3_CONN_TX2_P")
			(pintype "passive")
		)
		(pad "2" smd roundrect
			(at 0.48 0 180)
			(size 0.59 0.64)
			(layers "F.Cu" "F.Mask" "F.Paste")
			(roundrect_rratio 0.25)
			(net 285 "/USB Hub/USBC3_TX_{2}-")
			(pintype "passive")
		)
	)
	(footprint "antmicro-footprints:R_0805_2012Metric"
		(layer "F.Cu")
		(at 170.774468 131.24 180)
		(property "Reference" "R258"
			(at 1.974468 0.34 0)
			(layer "F.SilkS")
			(effects
				(font
					(size 0.7 0.7)
					(thickness 0.15)
				)
				(justify right top)
			)
		)
		(property "Value" "R_0R001_0805"
			(at 0 1.8 0)
			(layer "F.Fab")
			(effects
				(font
					(size 0.7 0.7)
					(thickness 0.15)
				)
				(justify right top)
			)
		)
		(property "Datasheet" "https://www.eaton.com/content/dam/eaton/products/electronic-components/resources/data-sheet/eaton-msma-automotive-smd-current-sense-resistor-metal-strip-data-sheet-elx1179.pdf"
			(at 0 0 0)
			(layer "F.Fab")
			(hide yes)
			(effects
				(font
					(size 1.27 1.27)
					(thickness 0.15)
				)
			)
		)
		(property "Description" "Current Sense Resistors - SMD MSMA, 0805 SIZE, 1/2 Watt, 1 mohm, 50 TCR MnCu Metal AEC-Q"
			(at 0 0 0)
			(layer "F.Fab")
			(hide yes)
			(effects
				(font
					(size 1.27 1.27)
					(thickness 0.15)
				)
			)
		)
		(property "MPN" "MSMA0805R0010FSM"
			(at 0 0 0)
			(unlocked yes)
			(layer "F.Fab")
			(hide yes)
			(effects
				(font
					(size 1 1)
					(thickness 0.15)
				)
			)
		)
		(property "Manufacturer" "Eaton"
			(at 0 0 0)
			(unlocked yes)
			(layer "F.Fab")
			(hide yes)
			(effects
				(font
					(size 1 1)
					(thickness 0.15)
				)
			)
		)
		(property "License" "Apache-2.0"
			(at 0 0 0)
			(unlocked yes)
			(layer "F.Fab")
			(hide yes)
			(effects
				(font
					(size 1 1)
					(thickness 0.15)
				)
			)
		)
		(property "Author" "Antmicro"
			(at 0 0 0)
			(unlocked yes)
			(layer "F.Fab")
			(hide yes)
			(effects
				(font
					(size 1 1)
					(thickness 0.15)
				)
			)
		)
		(property "Val" "0R001"
			(at 0 0 0)
			(unlocked yes)
			(layer "F.Fab")
			(hide yes)
			(effects
				(font
					(size 1 1)
					(thickness 0.15)
				)
			)
		)
		(property "Tolerance" "1%"
			(at 0 0 0)
			(unlocked yes)
			(layer "F.Fab")
			(hide yes)
			(effects
				(font
					(size 1 1)
					(thickness 0.15)
				)
			)
		)
		(property "Public" "False"
			(at 0 0 0)
			(unlocked yes)
			(layer "F.Fab")
			(hide yes)
			(effects
				(font
					(size 1 1)
					(thickness 0.15)
				)
			)
		)
		(sheetname "/DCDC/")
		(sheetfile "dcdc.kicad_sch")
		(attr smd)
		(fp_line
			(start -0.3 -0.701)
			(end 0.298 -0.701)
			(stroke
				(width 0.15)
				(type solid)
			)
			(layer "F.SilkS")
		)
		(fp_line
			(start -0.32 0.699)
			(end 0.28 0.699)
			(stroke
				(width 0.15)
				(type solid)
			)
			(layer "F.SilkS")
		)
		(fp_rect
			(start 1.95 -0.9)
			(end -1.95 0.9)
			(stroke
				(width 0.05)
				(type default)
			)
			(fill no)
			(layer "F.CrtYd")
		)
		(fp_line
			(start 0.949 -0.677)
			(end 0.949 0.675)
			(stroke
				(width 0.15)
				(type solid)
			)
			(layer "F.Fab")
		)
		(fp_line
			(start -0.951 0.68)
			(end 0.949 0.68)
			(stroke
				(width 0.15)
				(type solid)
			)
			(layer "F.Fab")
		)
		(fp_line
			(start -0.951 -0.677)
			(end -0.951 0.675)
			(stroke
				(width 0.15)
				(type solid)
			)
			(layer "F.Fab")
		)
		(fp_line
			(start -0.951 -0.682)
			(end 0.949 -0.682)
			(stroke
				(width 0.15)
				(type solid)
			)
			(layer "F.Fab")
		)
		(fp_text user "${REFERENCE}"
			(at -1.9 3.1 0)
			(layer "F.Fab")
			(effects
				(font
					(size 0.7 0.7)
					(thickness 0.15)
				)
				(justify right top)
			)
		)
		(fp_text user "Author: Antmicro"
			(at -1.9 4.4 0)
			(layer "F.Fab")
			(effects
				(font
					(size 0.7 0.7)
					(thickness 0.15)
				)
				(justify right top)
			)
		)
		(fp_text user "License: Apache-2.0"
			(at -1.9 5.75 0)
			(layer "F.Fab")
			(effects
				(font
					(size 0.7 0.7)
					(thickness 0.15)
				)
				(justify right top)
			)
		)
		(pad "1" smd roundrect
			(at -1.1 0 180)
			(size 1.2 1.3)
			(layers "F.Cu" "F.Mask" "F.Paste")
			(roundrect_rratio 0.25)
			(net 567 "/DCDC/3V3_OUT")
			(pintype "passive")
		)
		(pad "2" smd roundrect
			(at 1.1 0 180)
			(size 1.2 1.3)
			(layers "F.Cu" "F.Mask" "F.Paste")
			(roundrect_rratio 0.25)
			(net 2 "+3V3")
			(pintype "passive")
		)
	)
)
